# SCM (Grand Teton) — schematic netlist excerpt (pin names and nets, part order shuffled) for the footprints in the layout excerpt that follows; sources: Cadence DE-HDL packaged netlist, KiCad conversion of 12092022_DA0F0TMDCD0_F0T_Management_Board_D_brd_V3_OCP.brd

R187  Q_RES  33.2 1% CHIP  pkg 0402LF  page 14 : A = I3C2_SPD_SDA ; B = I3C2_SDA_R
R136  Q_RES  10K 1% CHIP  pkg 0402LF  page 46 : A = P3V3_AUX ; B = SMB_PCH_TPM_SCL

(kicad_pcb
	(version 20260206)
	(generator "pcbnew")
	(generator_version "10.0")
	(general
		(thickness 1.6)
		(legacy_teardrops no)
	)
	(paper "A4")
	(title_block
		(title "12092022_DA0F0TMDCD0_F0T_Management_Board_D_brd_V3_OCP.brd")
		(comment 1 "Grand Teton / footprints 366-367 of 1440")
	)
	(layers
		(0 "F.Cu" signal "TOP")
		(4 "In1.Cu" signal "GND")
		(6 "In2.Cu" signal "IN1")
		(8 "In3.Cu" signal "GND1")
		(10 "In4.Cu" signal "IN2")
		(12 "In5.Cu" signal "VCC")
		(14 "In6.Cu" signal "VCC1")
		(16 "In7.Cu" signal "IN3")
		(18 "In8.Cu" signal "GND2")
		(20 "In9.Cu" signal "IN4")
		(22 "In10.Cu" signal "GND3")
		(2 "B.Cu" signal "BOTTOM")
		(9 "F.Adhes" user "F.Adhesive")
		(11 "B.Adhes" user "B.Adhesive")
		(13 "F.Paste" user "Package Geometry/Pastemask Top")
		(15 "B.Paste" user "Package Geometry/Pastemask Bottom")
		(5 "F.SilkS" user "Ref Des/Silkscreen Top")
		(7 "B.SilkS" user "Ref Des/Silkscreen Bottom")
		(1 "F.Mask" user "Board Geometry/Soldermask Top")
		(3 "B.Mask" user "Board Geometry/Soldermask Bottom")
		(17 "Dwgs.User" user "User.Drawings")
		(19 "Cmts.User" user "User.Comments")
		(21 "Eco1.User" user "User.Eco1")
		(23 "Eco2.User" user "User.Eco2")
		(25 "Edge.Cuts" user "Board Geometry/Outline")
		(27 "Margin" user)
		(31 "F.CrtYd" user "Package Geometry/Place Bound Top")
		(29 "B.CrtYd" user "Package Geometry/Place Bound Bottom")
		(35 "F.Fab" user "Ref Des/Assembly Top")
		(33 "B.Fab" user "Ref Des/Assembly Bottom")
	)
	(footprint ""
		(layer "F.Cu")
		(at 57.18302 -97.34804)
		(property "Reference" "R136"
			(at 0 0 0)
			(layer "F.SilkS")
			(hide yes)
			(effects
				(font
					(size 1.27 1.27)
				)
			)
		)
		(property "Value" ""
			(at 0 0 0)
			(layer "F.Fab")
			(effects
				(font
					(size 1.27 1.27)
				)
			)
		)
		(duplicate_pad_numbers_are_jumpers no)
		(fp_line
			(start -0.7874 -0.4064)
			(end 0.7874 -0.4064)
			(stroke
				(width 0.1524)
				(type default)
			)
			(layer "F.SilkS")
		)
		(fp_line
			(start -0.7874 0.4064)
			(end -0.7874 -0.4064)
			(stroke
				(width 0.1524)
				(type default)
			)
			(layer "F.SilkS")
		)
		(fp_line
			(start 0.7874 -0.4064)
			(end 0.7874 0.4064)
			(stroke
				(width 0.1524)
				(type default)
			)
			(layer "F.SilkS")
		)
		(fp_line
			(start 0.7874 0.4064)
			(end -0.7874 0.4064)
			(stroke
				(width 0.1524)
				(type default)
			)
			(layer "F.SilkS")
		)
		(fp_line
			(start -0.67945 -0.305054)
			(end -0.12065 -0.305054)
			(stroke
				(width 0.1)
				(type default)
			)
			(layer "F.Fab")
		)
		(fp_line
			(start -0.67945 0.3048)
			(end -0.67945 -0.305054)
			(stroke
				(width 0.1)
				(type default)
			)
			(layer "F.Fab")
		)
		(fp_line
			(start -0.12065 -0.305054)
			(end -0.12065 -0.2794)
			(stroke
				(width 0.1)
				(type default)
			)
			(layer "F.Fab")
		)
		(fp_line
			(start -0.12065 -0.2794)
			(end 0.12065 -0.2794)
			(stroke
				(width 0.1)
				(type default)
			)
			(layer "F.Fab")
		)
		(fp_line
			(start -0.12065 0.2794)
			(end -0.12065 0.3048)
			(stroke
				(width 0.1)
				(type default)
			)
			(layer "F.Fab")
		)
		(fp_line
			(start -0.12065 0.3048)
			(end -0.67945 0.3048)
			(stroke
				(width 0.1)
				(type default)
			)
			(layer "F.Fab")
		)
		(fp_line
			(start 0.120396 0.2794)
			(end -0.12065 0.2794)
			(stroke
				(width 0.1)
				(type default)
			)
			(layer "F.Fab")
		)
		(fp_line
			(start 0.120396 0.3048)
			(end 0.120396 0.2794)
			(stroke
				(width 0.1)
				(type default)
			)
			(layer "F.Fab")
		)
		(fp_line
			(start 0.12065 -0.3048)
			(end 0.67945 -0.3048)
			(stroke
				(width 0.1)
				(type default)
			)
			(layer "F.Fab")
		)
		(fp_line
			(start 0.12065 -0.2794)
			(end 0.12065 -0.3048)
			(stroke
				(width 0.1)
				(type default)
			)
			(layer "F.Fab")
		)
		(fp_line
			(start 0.67945 -0.3048)
			(end 0.67945 0.3048)
			(stroke
				(width 0.1)
				(type default)
			)
			(layer "F.Fab")
		)
		(fp_line
			(start 0.67945 0.3048)
			(end 0.120396 0.3048)
			(stroke
				(width 0.1)
				(type default)
			)
			(layer "F.Fab")
		)
		(pad "1" smd circle
			(at -0.40005 0)
			(size 0 0)
			(layers "F.Cu" "F.Mask" "F.Paste")
			(net "P3V3_AUX")
		)
		(pad "2" smd circle
			(at 0.40005 0)
			(size 0 0)
			(layers "F.Cu" "F.Mask" "F.Paste")
			(net "SMB_PCH_TPM_SCL")
		)
	)
	(footprint ""
		(layer "F.Cu")
		(at 43.171618 -65.776094 -90)
		(property "Reference" "R187"
			(at 0 0 270)
			(layer "F.SilkS")
			(hide yes)
			(effects
				(font
					(size 1.27 1.27)
				)
			)
		)
		(property "Value" ""
			(at 0 0 270)
			(layer "F.Fab")
			(effects
				(font
					(size 1.27 1.27)
				)
			)
		)
		(duplicate_pad_numbers_are_jumpers no)
		(fp_line
			(start -0.7874 0.4064)
			(end -0.7874 -0.4064)
			(stroke
				(width 0.1524)
				(type default)
			)
			(layer "F.SilkS")
		)
		(fp_line
			(start 0.7874 0.4064)
			(end -0.7874 0.4064)
			(stroke
				(width 0.1524)
				(type default)
			)
			(layer "F.SilkS")
		)
		(fp_line
			(start -0.7874 -0.4064)
			(end 0.7874 -0.4064)
			(stroke
				(width 0.1524)
				(type default)
			)
			(layer "F.SilkS")
		)
		(fp_line
			(start 0.7874 -0.4064)
			(end 0.7874 0.4064)
			(stroke
				(width 0.1524)
				(type default)
			)
			(layer "F.SilkS")
		)
		(fp_line
			(start -0.67945 0.3048)
			(end -0.67945 -0.305054)
			(stroke
				(width 0.1)
				(type default)
			)
			(layer "F.Fab")
		)
		(fp_line
			(start -0.12065 0.3048)
			(end -0.67945 0.3048)
			(stroke
				(width 0.1)
				(type default)
			)
			(layer "F.Fab")
		)
		(fp_line
			(start 0.120396 0.3048)
			(end 0.120396 0.2794)
			(stroke
				(width 0.1)
				(type default)
			)
			(layer "F.Fab")
		)
		(fp_line
			(start 0.67945 0.3048)
			(end 0.120396 0.3048)
			(stroke
				(width 0.1)
				(type default)
			)
			(layer "F.Fab")
		)
		(fp_line
			(start -0.12065 0.2794)
			(end -0.12065 0.3048)
			(stroke
				(width 0.1)
				(type default)
			)
			(layer "F.Fab")
		)
		(fp_line
			(start 0.120396 0.2794)
			(end -0.12065 0.2794)
			(stroke
				(width 0.1)
				(type default)
			)
			(layer "F.Fab")
		)
		(fp_line
			(start -0.12065 -0.2794)
			(end 0.12065 -0.2794)
			(stroke
				(width 0.1)
				(type default)
			)
			(layer "F.Fab")
		)
		(fp_line
			(start 0.12065 -0.2794)
			(end 0.12065 -0.3048)
			(stroke
				(width 0.1)
				(type default)
			)
			(layer "F.Fab")
		)
		(fp_line
			(start 0.12065 -0.3048)
			(end 0.67945 -0.3048)
			(stroke
				(width 0.1)
				(type default)
			)
			(layer "F.Fab")
		)
		(fp_line
			(start 0.67945 -0.3048)
			(end 0.67945 0.3048)
			(stroke
				(width 0.1)
				(type default)
			)
			(layer "F.Fab")
		)
		(fp_line
			(start -0.67945 -0.305054)
			(end -0.12065 -0.305054)
			(stroke
				(width 0.1)
				(type default)
			)
			(layer "F.Fab")
		)
		(fp_line
			(start -0.12065 -0.305054)
			(end -0.12065 -0.2794)
			(stroke
				(width 0.1)
				(type default)
			)
			(layer "F.Fab")
		)
		(pad "1" smd circle
			(at -0.40005 0 270)
			(size 0 0)
			(layers "F.Cu" "F.Mask" "F.Paste")
			(net "I3C2_SPD_SDA")
		)
		(pad "2" smd circle
			(at 0.40005 0 270)
			(size 0 0)
			(layers "F.Cu" "F.Mask" "F.Paste")
			(net "I3C2_SDA_R")
		)
	)
)
